(kicad_pcb
	(version 20260206)
	(generator "pcbnew")
	(generator_version "10.0")
	(general
		(thickness 1.6)
		(legacy_teardrops no)
	)
	(paper "A4")
	(title_block
		(title "dpb — 14545-sa.0730WZS0815.brd")
		(comment 1 "Honey Badger (Wiwynn) / footprints 779-786 of 1066")
	)
	(layers
		(0 "F.Cu" signal "TOP")
		(4 "In1.Cu" signal "L2GND")
		(6 "In2.Cu" signal "L3")
		(8 "In3.Cu" signal "L4VCC")
		(10 "In4.Cu" signal "L5VCC")
		(12 "In5.Cu" signal "L6")
		(14 "In6.Cu" signal "L7GND")
		(2 "B.Cu" signal "BOTTOM")
		(9 "F.Adhes" user "F.Adhesive")
		(11 "B.Adhes" user "B.Adhesive")
		(13 "F.Paste" user "Package Geometry/Pastemask Top")
		(15 "B.Paste" user "Package Geometry/Pastemask Bottom")
		(5 "F.SilkS" user "Ref Des/Silkscreen Top")
		(7 "B.SilkS" user "Ref Des/Silkscreen Bottom")
		(1 "F.Mask" user "Board Geometry/Soldermask Top")
		(3 "B.Mask" user "Board Geometry/Soldermask Bottom")
		(17 "Dwgs.User" user "User.Drawings")
		(19 "Cmts.User" user "User.Comments")
		(21 "Eco1.User" user "User.Eco1")
		(23 "Eco2.User" user "User.Eco2")
		(25 "Edge.Cuts" user "Board Geometry/Outline")
		(27 "Margin" user)
		(31 "F.CrtYd" user "Package Geometry/Place Bound Top")
		(29 "B.CrtYd" user "Package Geometry/Place Bound Bottom")
		(35 "F.Fab" user "Ref Des/Assembly Top")
		(33 "B.Fab" user "Ref Des/Assembly Bottom")
	)
	(footprint ""
		(layer "F.Cu")
		(at 7.499858 -261.499858)
		(property "Reference" "H7"
			(at 0 0 0)
			(layer "F.SilkS")
			(hide yes)
			(effects
				(font
					(size 1.27 1.27)
				)
			)
		)
		(property "Value" "HOLE315R140"
			(at 0 -7.5692 0)
			(unlocked yes)
			(layer "F.Fab")
			(hide yes)
			(effects
				(font
					(size 1.016 1.016)
					(thickness 0.1524)
				)
			)
		)
		(property "Device Type" "HOLE315R140"
			(at 0 -9.0932 0)
			(unlocked yes)
			(layer "F.Fab")
			(hide yes)
			(effects
				(font
					(size 1.016 1.016)
					(thickness 0.1524)
				)
			)
		)
		(duplicate_pad_numbers_are_jumpers no)
		(fp_poly
			(pts
				(arc
					(start 4.3053 0)
					(mid -4.3053 0)
					(end 4.3053 0)
				)
			)
			(stroke
				(width 0)
				(type default)
			)
			(fill no)
			(layer "F.CrtYd")
		)
		(fp_poly
			(pts
				(arc
					(start 4.3053 0)
					(mid -4.3053 0)
					(end 4.3053 0)
				)
			)
			(stroke
				(width 0)
				(type default)
			)
			(fill no)
			(layer "F.Fab")
		)
		(pad "1" thru_hole circle
			(at 0.00127 0.00127)
			(size 8.001 8.001)
			(drill 3.556)
			(layers "*.Cu" "*.Mask")
			(remove_unused_layers no)
			(net "GND")
			(clearance -1.7145)
			(thermal_gap 0.3048)
			(padstack
				(mode front_inner_back)
				(layer "Inner"
					(shape circle)
					(size 3.9624 3.9624)
					(clearance 0.3048)
				)
				(layer "B.Cu"
					(shape circle)
					(size 8.001 8.001)
					(clearance -1.7145)
				)
			)
		)
	)
	(footprint ""
		(layer "F.Cu")
		(at 217.762582 -264.005568 -90)
		(property "Reference" "C135"
			(at 0 0 270)
			(layer "F.SilkS")
			(hide yes)
			(effects
				(font
					(size 1.27 1.27)
				)
			)
		)
		(property "Value" "SCD01U50V2KX-1GP"
			(at 1.1811 -2.7051 270)
			(unlocked yes)
			(layer "F.Fab")
			(hide yes)
			(effects
				(font
					(size 1.016 1.016)
					(thickness 0.1524)
				)
			)
		)
		(property "Device Type" "C402H22"
			(at 1.1811 -4.2291 270)
			(unlocked yes)
			(layer "F.Fab")
			(hide yes)
			(effects
				(font
					(size 1.016 1.016)
					(thickness 0.1524)
				)
			)
		)
		(duplicate_pad_numbers_are_jumpers no)
		(fp_rect
			(start -0.4318 0.9525)
			(end 0.4318 -0.9525)
			(stroke
				(width 0)
				(type default)
			)
			(fill no)
			(layer "F.CrtYd")
		)
		(fp_rect
			(start -0.4318 0.9525)
			(end 0.4318 -0.9525)
			(stroke
				(width 0)
				(type default)
			)
			(fill no)
			(layer "F.Fab")
		)
		(pad "1" smd custom
			(at 0 -0.4445 270)
			(size 0.1524 0.1524)
			(layers "F.Cu" "F.Mask" "F.Paste")
			(net "SAS2X28_DRIVE_RX_P_A2")
			(options
				(clearance outline)
				(anchor circle)
			)
			(primitives
				(gr_poly
					(pts
						(arc
							(start 0.3048 -0.2032)
							(mid 0.275042 -0.275042)
							(end 0.2032 -0.3048)
						)
						(arc
							(start -0.2032 -0.3048)
							(mid -0.275042 -0.275042)
							(end -0.3048 -0.2032)
						)
						(arc
							(start -0.3048 0.2032)
							(mid -0.275042 0.275042)
							(end -0.2032 0.3048)
						)
						(arc
							(start 0.2032 0.3048)
							(mid 0.275042 0.275042)
							(end 0.3048 0.2032)
						)
					)
					(width 0)
					(fill yes)
				)
			)
		)
		(pad "2" smd custom
			(at 0 0.4445 270)
			(size 0.1524 0.1524)
			(layers "F.Cu" "F.Mask" "F.Paste")
			(net "SAS2X28_A_HDD2_RX_+")
			(options
				(clearance outline)
				(anchor circle)
			)
			(primitives
				(gr_poly
					(pts
						(arc
							(start 0.3048 -0.2032)
							(mid 0.275042 -0.275042)
							(end 0.2032 -0.3048)
						)
						(arc
							(start -0.2032 -0.3048)
							(mid -0.275042 -0.275042)
							(end -0.3048 -0.2032)
						)
						(arc
							(start -0.3048 0.2032)
							(mid -0.275042 0.275042)
							(end -0.2032 0.3048)
						)
						(arc
							(start 0.2032 0.3048)
							(mid 0.275042 0.275042)
							(end 0.3048 0.2032)
						)
					)
					(width 0)
					(fill yes)
				)
			)
		)
	)
	(footprint ""
		(layer "F.Cu")
		(at 216.492582 -275.435568)
		(property "Reference" "R139"
			(at 0 0 0)
			(layer "F.SilkS")
			(hide yes)
			(effects
				(font
					(size 1.27 1.27)
				)
			)
		)
		(property "Value" "220R3F-1-GP"
			(at -0.0254 -2.5146 0)
			(unlocked yes)
			(layer "F.Fab")
			(hide yes)
			(effects
				(font
					(size 1.016 1.016)
					(thickness 0.1524)
				)
			)
		)
		(property "Device Type" "R603H22"
			(at -0.0254 -4.0386 0)
			(unlocked yes)
			(layer "F.Fab")
			(hide yes)
			(effects
				(font
					(size 1.016 1.016)
					(thickness 0.1524)
				)
			)
		)
		(duplicate_pad_numbers_are_jumpers no)
		(fp_line
			(start -0.4826 0)
			(end -0.2032 0)
			(stroke
				(width 0.2032)
				(type default)
			)
			(layer "F.SilkS")
		)
		(fp_line
			(start 0.2032 0)
			(end 0.4826 0)
			(stroke
				(width 0.2032)
				(type default)
			)
			(layer "F.SilkS")
		)
		(fp_rect
			(start -0.5842 1.3335)
			(end 0.5842 -1.3335)
			(stroke
				(width 0)
				(type default)
			)
			(fill no)
			(layer "F.CrtYd")
		)
		(fp_rect
			(start -0.5842 1.3335)
			(end 0.5842 -1.3335)
			(stroke
				(width 0)
				(type default)
			)
			(fill no)
			(layer "F.Fab")
		)
		(pad "1" smd custom
			(at 0 -0.762)
			(size 0.2159 0.2159)
			(layers "F.Cu" "F.Mask" "F.Paste")
			(net "HDD_PRSNT_NET2")
			(options
				(clearance outline)
				(anchor circle)
			)
			(primitives
				(gr_poly
					(pts
						(arc
							(start -0.3302 -0.4318)
							(mid -0.402042 -0.402042)
							(end -0.4318 -0.3302)
						)
						(arc
							(start -0.4318 0.3302)
							(mid -0.402042 0.402042)
							(end -0.3302 0.4318)
						)
						(arc
							(start 0.3302 0.4318)
							(mid 0.402042 0.402042)
							(end 0.4318 0.3302)
						)
						(arc
							(start 0.4318 -0.3302)
							(mid 0.402042 -0.402042)
							(end 0.3302 -0.4318)
						)
					)
					(width 0)
					(fill yes)
				)
			)
		)
		(pad "2" smd custom
			(at 0 0.762)
			(size 0.2159 0.2159)
			(layers "F.Cu" "F.Mask" "F.Paste")
			(net "HDD_PRSNT2")
			(options
				(clearance outline)
				(anchor circle)
			)
			(primitives
				(gr_poly
					(pts
						(arc
							(start -0.3302 -0.4318)
							(mid -0.402042 -0.402042)
							(end -0.4318 -0.3302)
						)
						(arc
							(start -0.4318 0.3302)
							(mid -0.402042 0.402042)
							(end -0.3302 0.4318)
						)
						(arc
							(start 0.3302 0.4318)
							(mid 0.402042 0.402042)
							(end 0.4318 0.3302)
						)
						(arc
							(start 0.4318 -0.3302)
							(mid 0.402042 -0.402042)
							(end 0.3302 -0.4318)
						)
					)
					(width 0)
					(fill yes)
				)
			)
		)
	)
	(footprint ""
		(layer "F.Cu")
		(at 27.431746 -330.482702 180)
		(property "Reference" "R265"
			(at 0 0 180)
			(layer "F.SilkS")
			(hide yes)
			(effects
				(font
					(size 1.27 1.27)
				)
			)
		)
		(property "Value" "220R3F-1-GP"
			(at -0.0254 -2.5146 180)
			(unlocked yes)
			(layer "F.Fab")
			(hide yes)
			(effects
				(font
					(size 1.016 1.016)
					(thickness 0.1524)
				)
			)
		)
		(property "Device Type" "R603H22"
			(at -0.0254 -4.0386 180)
			(unlocked yes)
			(layer "F.Fab")
			(hide yes)
			(effects
				(font
					(size 1.016 1.016)
					(thickness 0.1524)
				)
			)
		)
		(duplicate_pad_numbers_are_jumpers no)
		(fp_line
			(start 0.2032 0)
			(end 0.4826 0)
			(stroke
				(width 0.2032)
				(type default)
			)
			(layer "F.SilkS")
		)
		(fp_line
			(start -0.4826 0)
			(end -0.2032 0)
			(stroke
				(width 0.2032)
				(type default)
			)
			(layer "F.SilkS")
		)
		(fp_rect
			(start -0.5842 1.3335)
			(end 0.5842 -1.3335)
			(stroke
				(width 0)
				(type default)
			)
			(fill no)
			(layer "F.CrtYd")
		)
		(fp_rect
			(start -0.5842 1.3335)
			(end 0.5842 -1.3335)
			(stroke
				(width 0)
				(type default)
			)
			(fill no)
			(layer "F.Fab")
		)
		(pad "1" smd custom
			(at 0 -0.762 180)
			(size 0.2159 0.2159)
			(layers "F.Cu" "F.Mask" "F.Paste")
			(net "HDD_PRSNT_NET11")
			(options
				(clearance outline)
				(anchor circle)
			)
			(primitives
				(gr_poly
					(pts
						(arc
							(start -0.3302 -0.4318)
							(mid -0.402042 -0.402042)
							(end -0.4318 -0.3302)
						)
						(arc
							(start -0.4318 0.3302)
							(mid -0.402042 0.402042)
							(end -0.3302 0.4318)
						)
						(arc
							(start 0.3302 0.4318)
							(mid 0.402042 0.402042)
							(end 0.4318 0.3302)
						)
						(arc
							(start 0.4318 -0.3302)
							(mid 0.402042 -0.402042)
							(end 0.3302 -0.4318)
						)
					)
					(width 0)
					(fill yes)
				)
			)
		)
		(pad "2" smd custom
			(at 0 0.762 180)
			(size 0.2159 0.2159)
			(layers "F.Cu" "F.Mask" "F.Paste")
			(net "HDD_PRSNT11")
			(options
				(clearance outline)
				(anchor circle)
			)
			(primitives
				(gr_poly
					(pts
						(arc
							(start -0.3302 -0.4318)
							(mid -0.402042 -0.402042)
							(end -0.4318 -0.3302)
						)
						(arc
							(start -0.4318 0.3302)
							(mid -0.402042 0.402042)
							(end -0.3302 0.4318)
						)
						(arc
							(start 0.3302 0.4318)
							(mid 0.402042 0.402042)
							(end 0.4318 0.3302)
						)
						(arc
							(start 0.4318 -0.3302)
							(mid 0.402042 -0.402042)
							(end 0.3302 -0.4318)
						)
					)
					(width 0)
					(fill yes)
				)
			)
		)
	)
	(footprint ""
		(layer "F.Cu")
		(at 29.590746 -430.050702 90)
		(property "Reference" "R245"
			(at 0 0 90)
			(layer "F.SilkS")
			(hide yes)
			(effects
				(font
					(size 1.27 1.27)
				)
			)
		)
		(property "Value" "2R2010J-1-GP"
			(at 0.254 -8.0772 90)
			(unlocked yes)
			(layer "F.Fab")
			(hide yes)
			(effects
				(font
					(size 1.016 1.016)
					(thickness 0.1524)
				)
			)
		)
		(property "Device Type" "R2010H28"
			(at 0.254 -9.6774 90)
			(unlocked yes)
			(layer "F.Fab")
			(hide yes)
			(effects
				(font
					(size 1.016 1.016)
					(thickness 0.1524)
				)
			)
		)
		(duplicate_pad_numbers_are_jumpers no)
		(fp_line
			(start 1.651 -3.302)
			(end -1.651 -3.302)
			(stroke
				(width 0.1524)
				(type default)
			)
			(layer "F.SilkS")
		)
		(fp_line
			(start -1.651 -3.302)
			(end -1.651 3.302)
			(stroke
				(width 0.1524)
				(type default)
			)
			(layer "F.SilkS")
		)
		(fp_line
			(start 1.651 3.302)
			(end 1.651 -3.302)
			(stroke
				(width 0.1524)
				(type default)
			)
			(layer "F.SilkS")
		)
		(fp_line
			(start -1.651 3.302)
			(end 1.651 3.302)
			(stroke
				(width 0.1524)
				(type default)
			)
			(layer "F.SilkS")
		)
		(fp_rect
			(start -1.7272 -3.3782)
			(end 1.7272 3.3782)
			(stroke
				(width 0)
				(type default)
			)
			(fill no)
			(layer "F.CrtYd")
		)
		(fp_poly
			(pts
				(xy 1.7272 3.3782) (xy 1.7272 -3.3782) (xy -1.7272 -3.3782) (xy -1.7272 3.3782)
			)
			(stroke
				(width 0)
				(type default)
			)
			(fill no)
			(layer "F.Fab")
		)
		(pad "1" smd rect
			(at 0 -2.3495 90)
			(size 2.794 1.143)
			(layers "F.Cu" "F.Mask" "F.Paste")
			(net "5V_PRE_10")
		)
		(pad "2" smd rect
			(at 0 2.3495 90)
			(size 2.794 1.143)
			(layers "F.Cu" "F.Mask" "F.Paste")
			(net "P5V_HDD10")
		)
	)
	(footprint ""
		(layer "F.Cu")
		(at 60.3758 -396.9004 180)
		(property "Reference" "C208"
			(at 0 0 180)
			(layer "F.SilkS")
			(hide yes)
			(effects
				(font
					(size 1.27 1.27)
				)
			)
		)
		(property "Value" "SC10U25V6KX-1GP"
			(at -0.0762 -5.1308 180)
			(unlocked yes)
			(layer "F.Fab")
			(hide yes)
			(effects
				(font
					(size 1.016 1.016)
					(thickness 0.1524)
				)
			)
		)
		(property "Device Type" "C1206H71"
			(at -0.127 -6.6548 180)
			(unlocked yes)
			(layer "F.Fab")
			(hide yes)
			(effects
				(font
					(size 1.016 1.016)
					(thickness 0.1524)
				)
			)
		)
		(duplicate_pad_numbers_are_jumpers no)
		(fp_line
			(start 1.016 2.2352)
			(end -1.016 2.2352)
			(stroke
				(width 0.1524)
				(type default)
			)
			(layer "F.SilkS")
		)
		(fp_line
			(start 1.016 0.8382)
			(end 1.016 2.2352)
			(stroke
				(width 0.1524)
				(type default)
			)
			(layer "F.SilkS")
		)
		(fp_line
			(start 1.016 -2.2352)
			(end 1.016 -0.8382)
			(stroke
				(width 0.1524)
				(type default)
			)
			(layer "F.SilkS")
		)
		(fp_line
			(start -1.016 2.2352)
			(end -1.016 0.8382)
			(stroke
				(width 0.1524)
				(type default)
			)
			(layer "F.SilkS")
		)
		(fp_line
			(start -1.016 -0.8382)
			(end -1.016 -2.2352)
			(stroke
				(width 0.1524)
				(type default)
			)
			(layer "F.SilkS")
		)
		(fp_line
			(start -1.016 -2.2352)
			(end 1.016 -2.2352)
			(stroke
				(width 0.1524)
				(type default)
			)
			(layer "F.SilkS")
		)
		(fp_rect
			(start -1.0922 2.3114)
			(end 1.0922 -2.3114)
			(stroke
				(width 0)
				(type default)
			)
			(fill no)
			(layer "F.CrtYd")
		)
		(fp_poly
			(pts
				(xy 1.0922 -2.3114) (xy 1.0922 2.3114) (xy -1.0922 2.3114) (xy -1.0922 -2.3114)
			)
			(stroke
				(width 0)
				(type default)
			)
			(fill no)
			(layer "F.Fab")
		)
		(pad "1" smd rect
			(at 0 -1.397 180)
			(size 1.651 1.27)
			(layers "F.Cu" "F.Mask" "F.Paste")
			(net "P12V_HDD6")
		)
		(pad "2" smd rect
			(at 0 1.397 180)
			(size 1.651 1.27)
			(layers "F.Cu" "F.Mask" "F.Paste")
			(net "GND")
		)
	)
	(footprint ""
		(layer "F.Cu")
		(at 79.628746 -490.2327)
		(property "Reference" "C181"
			(at 0 0 0)
			(layer "F.SilkS")
			(hide yes)
			(effects
				(font
					(size 1.27 1.27)
				)
			)
		)
		(property "Value" "SCD1U10V2KX-5GP"
			(at 1.1811 -2.7051 0)
			(unlocked yes)
			(layer "F.Fab")
			(hide yes)
			(effects
				(font
					(size 1.016 1.016)
					(thickness 0.1524)
				)
			)
		)
		(property "Device Type" "C402H22"
			(at 1.1811 -4.2291 0)
			(unlocked yes)
			(layer "F.Fab")
			(hide yes)
			(effects
				(font
					(size 1.016 1.016)
					(thickness 0.1524)
				)
			)
		)
		(duplicate_pad_numbers_are_jumpers no)
		(fp_rect
			(start -0.4318 0.9525)
			(end 0.4318 -0.9525)
			(stroke
				(width 0)
				(type default)
			)
			(fill no)
			(layer "F.CrtYd")
		)
		(fp_rect
			(start -0.4318 0.9525)
			(end 0.4318 -0.9525)
			(stroke
				(width 0)
				(type default)
			)
			(fill no)
			(layer "F.Fab")
		)
		(pad "1" smd custom
			(at 0 -0.4445)
			(size 0.1524 0.1524)
			(layers "F.Cu" "F.Mask" "F.Paste")
			(net "P3V3")
			(options
				(clearance outline)
				(anchor circle)
			)
			(primitives
				(gr_poly
					(pts
						(arc
							(start 0.3048 -0.2032)
							(mid 0.275042 -0.275042)
							(end 0.2032 -0.3048)
						)
						(arc
							(start -0.2032 -0.3048)
							(mid -0.275042 -0.275042)
							(end -0.3048 -0.2032)
						)
						(arc
							(start -0.3048 0.2032)
							(mid -0.275042 0.275042)
							(end -0.2032 0.3048)
						)
						(arc
							(start 0.2032 0.3048)
							(mid 0.275042 0.275042)
							(end 0.3048 0.2032)
						)
					)
					(width 0)
					(fill yes)
				)
			)
		)
		(pad "2" smd custom
			(at 0 0.4445)
			(size 0.1524 0.1524)
			(layers "F.Cu" "F.Mask" "F.Paste")
			(net "GND")
			(options
				(clearance outline)
				(anchor circle)
			)
			(primitives
				(gr_poly
					(pts
						(arc
							(start 0.3048 -0.2032)
							(mid 0.275042 -0.275042)
							(end 0.2032 -0.3048)
						)
						(arc
							(start -0.2032 -0.3048)
							(mid -0.275042 -0.275042)
							(end -0.3048 -0.2032)
						)
						(arc
							(start -0.3048 0.2032)
							(mid -0.275042 0.275042)
							(end -0.2032 0.3048)
						)
						(arc
							(start 0.2032 0.3048)
							(mid 0.275042 0.275042)
							(end 0.3048 0.2032)
						)
					)
					(width 0)
					(fill yes)
				)
			)
		)
	)
	(footprint ""
		(layer "F.Cu")
		(at 75.209146 -7.013702)
		(property "Reference" "C336"
			(at 0 0 0)
			(layer "F.SilkS")
			(hide yes)
			(effects
				(font
					(size 1.27 1.27)
				)
			)
		)
		(property "Value" "SC10U25V6KX-1GP"
			(at -0.0762 -5.1308 0)
			(unlocked yes)
			(layer "F.Fab")
			(hide yes)
			(effects
				(font
					(size 1.016 1.016)
					(thickness 0.1524)
				)
			)
		)
		(property "Device Type" "C1206H71"
			(at -0.127 -6.6548 0)
			(unlocked yes)
			(layer "F.Fab")
			(hide yes)
			(effects
				(font
					(size 1.016 1.016)
					(thickness 0.1524)
				)
			)
		)
		(duplicate_pad_numbers_are_jumpers no)
		(fp_line
			(start -1.016 -2.2352)
			(end 1.016 -2.2352)
			(stroke
				(width 0.1524)
				(type default)
			)
			(layer "F.SilkS")
		)
		(fp_line
			(start -1.016 -0.8382)
			(end -1.016 -2.2352)
			(stroke
				(width 0.1524)
				(type default)
			)
			(layer "F.SilkS")
		)
		(fp_line
			(start -1.016 2.2352)
			(end -1.016 0.8382)
			(stroke
				(width 0.1524)
				(type default)
			)
			(layer "F.SilkS")
		)
		(fp_line
			(start 1.016 -2.2352)
			(end 1.016 -0.8382)
			(stroke
				(width 0.1524)
				(type default)
			)
			(layer "F.SilkS")
		)
		(fp_line
			(start 1.016 0.8382)
			(end 1.016 2.2352)
			(stroke
				(width 0.1524)
				(type default)
			)
			(layer "F.SilkS")
		)
		(fp_line
			(start 1.016 2.2352)
			(end -1.016 2.2352)
			(stroke
				(width 0.1524)
				(type default)
			)
			(layer "F.SilkS")
		)
		(fp_rect
			(start -1.0922 2.3114)
			(end 1.0922 -2.3114)
			(stroke
				(width 0)
				(type default)
			)
			(fill no)
			(layer "F.CrtYd")
		)
		(fp_poly
			(pts
				(xy 1.0922 -2.3114) (xy 1.0922 2.3114) (xy -1.0922 2.3114) (xy -1.0922 -2.3114)
			)
			(stroke
				(width 0)
				(type default)
			)
			(fill no)
			(layer "F.Fab")
		)
		(pad "1" smd rect
			(at 0 -1.397)
			(size 1.651 1.27)
			(layers "F.Cu" "F.Mask" "F.Paste")
			(net "P12V_HDD14")
		)
		(pad "2" smd rect
			(at 0 1.397)
			(size 1.651 1.27)
			(layers "F.Cu" "F.Mask" "F.Paste")
			(net "GND")
		)
	)
)
